(kicad_pcb
	(version 20260206)
	(generator "pcbnew")
	(generator_version "10.0")
	(general
		(thickness 1.6)
		(legacy_teardrops no)
	)
	(paper "A4")
	(title_block
		(title "03242023_DA0F0TMBIJ0_F0T_Motherboard_J_brd_V01_OCP.brd")
		(comment 1 "Grand Teton / footprints 3864-3869 of 6105")
	)
	(layers
		(0 "F.Cu" signal "TOP")
		(4 "In1.Cu" signal "GND")
		(6 "In2.Cu" signal "IN1")
		(8 "In3.Cu" signal "GND1")
		(10 "In4.Cu" signal "IN2")
		(12 "In5.Cu" signal "GND2")
		(14 "In6.Cu" signal "IN3")
		(16 "In7.Cu" signal "GND3")
		(18 "In8.Cu" signal "VCC")
		(20 "In9.Cu" signal "VCC1")
		(22 "In10.Cu" signal "GND4")
		(24 "In11.Cu" signal "IN4")
		(26 "In12.Cu" signal "GND5")
		(28 "In13.Cu" signal "IN5")
		(30 "In14.Cu" signal "GND6")
		(32 "In15.Cu" signal "IN6")
		(34 "In16.Cu" signal "GND7")
		(2 "B.Cu" signal "BOTTOM")
		(9 "F.Adhes" user "F.Adhesive")
		(11 "B.Adhes" user "B.Adhesive")
		(13 "F.Paste" user "Package Geometry/Pastemask Top")
		(15 "B.Paste" user "Package Geometry/Pastemask Bottom")
		(5 "F.SilkS" user "Ref Des/Silkscreen Top")
		(7 "B.SilkS" user "Ref Des/Silkscreen Bottom")
		(1 "F.Mask" user "Board Geometry/Soldermask Top")
		(3 "B.Mask" user "Board Geometry/Soldermask Bottom")
		(17 "Dwgs.User" user "User.Drawings")
		(19 "Cmts.User" user "User.Comments")
		(21 "Eco1.User" user "User.Eco1")
		(23 "Eco2.User" user "User.Eco2")
		(25 "Edge.Cuts" user "Board Geometry/Outline")
		(27 "Margin" user)
		(31 "F.CrtYd" user "Package Geometry/Place Bound Top")
		(29 "B.CrtYd" user "Package Geometry/Place Bound Bottom")
		(35 "F.Fab" user "Ref Des/Assembly Top")
		(33 "B.Fab" user "Ref Des/Assembly Bottom")
	)
	(footprint ""
		(layer "F.Cu")
		(at 123.994926 -122.096784 90)
		(property "Reference" "C2253"
			(at 0 0 90)
			(layer "F.SilkS")
			(hide yes)
			(effects
				(font
					(size 1.27 1.27)
				)
			)
		)
		(property "Value" ""
			(at 0 0 90)
			(layer "F.Fab")
			(effects
				(font
					(size 1.27 1.27)
				)
			)
		)
		(duplicate_pad_numbers_are_jumpers no)
		(fp_line
			(start 0.7874 -0.4064)
			(end 0.7874 0.4064)
			(stroke
				(width 0.1524)
				(type default)
			)
			(layer "F.SilkS")
		)
		(fp_line
			(start -0.7874 -0.4064)
			(end 0.7874 -0.4064)
			(stroke
				(width 0.1524)
				(type default)
			)
			(layer "F.SilkS")
		)
		(fp_line
			(start 0.7874 0.4064)
			(end -0.7874 0.4064)
			(stroke
				(width 0.1524)
				(type default)
			)
			(layer "F.SilkS")
		)
		(fp_line
			(start -0.7874 0.4064)
			(end -0.7874 -0.4064)
			(stroke
				(width 0.1524)
				(type default)
			)
			(layer "F.SilkS")
		)
		(fp_line
			(start -0.12065 -0.305054)
			(end -0.12065 -0.2794)
			(stroke
				(width 0.1)
				(type default)
			)
			(layer "F.Fab")
		)
		(fp_line
			(start -0.67945 -0.305054)
			(end -0.12065 -0.305054)
			(stroke
				(width 0.1)
				(type default)
			)
			(layer "F.Fab")
		)
		(fp_line
			(start 0.67945 -0.3048)
			(end 0.67945 0.3048)
			(stroke
				(width 0.1)
				(type default)
			)
			(layer "F.Fab")
		)
		(fp_line
			(start 0.12065 -0.3048)
			(end 0.67945 -0.3048)
			(stroke
				(width 0.1)
				(type default)
			)
			(layer "F.Fab")
		)
		(fp_line
			(start 0.12065 -0.2794)
			(end 0.12065 -0.3048)
			(stroke
				(width 0.1)
				(type default)
			)
			(layer "F.Fab")
		)
		(fp_line
			(start -0.12065 -0.2794)
			(end 0.12065 -0.2794)
			(stroke
				(width 0.1)
				(type default)
			)
			(layer "F.Fab")
		)
		(fp_line
			(start 0.120396 0.2794)
			(end -0.12065 0.2794)
			(stroke
				(width 0.1)
				(type default)
			)
			(layer "F.Fab")
		)
		(fp_line
			(start -0.12065 0.2794)
			(end -0.12065 0.3048)
			(stroke
				(width 0.1)
				(type default)
			)
			(layer "F.Fab")
		)
		(fp_line
			(start 0.67945 0.3048)
			(end 0.120396 0.3048)
			(stroke
				(width 0.1)
				(type default)
			)
			(layer "F.Fab")
		)
		(fp_line
			(start 0.120396 0.3048)
			(end 0.120396 0.2794)
			(stroke
				(width 0.1)
				(type default)
			)
			(layer "F.Fab")
		)
		(fp_line
			(start -0.12065 0.3048)
			(end -0.67945 0.3048)
			(stroke
				(width 0.1)
				(type default)
			)
			(layer "F.Fab")
		)
		(fp_line
			(start -0.67945 0.3048)
			(end -0.67945 -0.305054)
			(stroke
				(width 0.1)
				(type default)
			)
			(layer "F.Fab")
		)
		(pad "1" smd circle
			(at -0.40005 0 90)
			(size 0 0)
			(layers "F.Cu" "F.Mask" "F.Paste")
			(net "P0V62_CPU1_RST_DDR_VREF")
		)
		(pad "2" smd circle
			(at 0.40005 0 90)
			(size 0 0)
			(layers "F.Cu" "F.Mask" "F.Paste")
			(net "GND")
		)
	)
	(footprint ""
		(layer "F.Cu")
		(at 416.54349 -408.517344 -90)
		(property "Reference" "C899"
			(at 0 0 270)
			(layer "F.SilkS")
			(hide yes)
			(effects
				(font
					(size 1.27 1.27)
				)
			)
		)
		(property "Value" ""
			(at 0 0 270)
			(layer "F.Fab")
			(effects
				(font
					(size 1.27 1.27)
				)
			)
		)
		(duplicate_pad_numbers_are_jumpers no)
		(fp_line
			(start -0.299974 0.150114)
			(end -0.299974 -0.150114)
			(stroke
				(width 0.1)
				(type default)
			)
			(layer "F.Fab")
		)
		(fp_line
			(start 0.299974 0.150114)
			(end -0.299974 0.150114)
			(stroke
				(width 0.1)
				(type default)
			)
			(layer "F.Fab")
		)
		(fp_line
			(start -0.299974 -0.150114)
			(end 0.299974 -0.150114)
			(stroke
				(width 0.1)
				(type default)
			)
			(layer "F.Fab")
		)
		(fp_line
			(start 0.299974 -0.150114)
			(end 0.299974 0.150114)
			(stroke
				(width 0.1)
				(type default)
			)
			(layer "F.Fab")
		)
		(pad "1" smd rect
			(at -0.2667 0 270)
			(size 0.3048 0.381)
			(layers "F.Cu" "F.Mask" "F.Paste")
			(net "P5E_CPU0_PE3_TX_C_DP<1>")
		)
		(pad "2" smd rect
			(at 0.2667 0 270)
			(size 0.3048 0.381)
			(layers "F.Cu" "F.Mask" "F.Paste")
			(net "P5E_CPU0_PE3_TX_DP<1>")
		)
	)
	(footprint ""
		(layer "F.Cu")
		(at 352.283014 -252.956314 -90)
		(property "Reference" "C998"
			(at 0 0 270)
			(layer "F.SilkS")
			(hide yes)
			(effects
				(font
					(size 1.27 1.27)
				)
			)
		)
		(property "Value" ""
			(at 0 0 270)
			(layer "F.Fab")
			(effects
				(font
					(size 1.27 1.27)
				)
			)
		)
		(duplicate_pad_numbers_are_jumpers no)
		(fp_line
			(start -0.7874 0.4064)
			(end -0.7874 -0.4064)
			(stroke
				(width 0.1524)
				(type default)
			)
			(layer "F.SilkS")
		)
		(fp_line
			(start 0.7874 0.4064)
			(end -0.7874 0.4064)
			(stroke
				(width 0.1524)
				(type default)
			)
			(layer "F.SilkS")
		)
		(fp_line
			(start -0.7874 -0.4064)
			(end 0.7874 -0.4064)
			(stroke
				(width 0.1524)
				(type default)
			)
			(layer "F.SilkS")
		)
		(fp_line
			(start 0.7874 -0.4064)
			(end 0.7874 0.4064)
			(stroke
				(width 0.1524)
				(type default)
			)
			(layer "F.SilkS")
		)
		(fp_line
			(start -0.67945 0.3048)
			(end -0.67945 -0.305054)
			(stroke
				(width 0.1)
				(type default)
			)
			(layer "F.Fab")
		)
		(fp_line
			(start -0.12065 0.3048)
			(end -0.67945 0.3048)
			(stroke
				(width 0.1)
				(type default)
			)
			(layer "F.Fab")
		)
		(fp_line
			(start 0.120396 0.3048)
			(end 0.120396 0.2794)
			(stroke
				(width 0.1)
				(type default)
			)
			(layer "F.Fab")
		)
		(fp_line
			(start 0.67945 0.3048)
			(end 0.120396 0.3048)
			(stroke
				(width 0.1)
				(type default)
			)
			(layer "F.Fab")
		)
		(fp_line
			(start -0.12065 0.2794)
			(end -0.12065 0.3048)
			(stroke
				(width 0.1)
				(type default)
			)
			(layer "F.Fab")
		)
		(fp_line
			(start 0.120396 0.2794)
			(end -0.12065 0.2794)
			(stroke
				(width 0.1)
				(type default)
			)
			(layer "F.Fab")
		)
		(fp_line
			(start -0.12065 -0.2794)
			(end 0.12065 -0.2794)
			(stroke
				(width 0.1)
				(type default)
			)
			(layer "F.Fab")
		)
		(fp_line
			(start 0.12065 -0.2794)
			(end 0.12065 -0.3048)
			(stroke
				(width 0.1)
				(type default)
			)
			(layer "F.Fab")
		)
		(fp_line
			(start 0.12065 -0.3048)
			(end 0.67945 -0.3048)
			(stroke
				(width 0.1)
				(type default)
			)
			(layer "F.Fab")
		)
		(fp_line
			(start 0.67945 -0.3048)
			(end 0.67945 0.3048)
			(stroke
				(width 0.1)
				(type default)
			)
			(layer "F.Fab")
		)
		(fp_line
			(start -0.67945 -0.305054)
			(end -0.12065 -0.305054)
			(stroke
				(width 0.1)
				(type default)
			)
			(layer "F.Fab")
		)
		(fp_line
			(start -0.12065 -0.305054)
			(end -0.12065 -0.2794)
			(stroke
				(width 0.1)
				(type default)
			)
			(layer "F.Fab")
		)
		(pad "1" smd circle
			(at -0.40005 0 270)
			(size 0 0)
			(layers "F.Cu" "F.Mask" "F.Paste")
			(net "PVCCIN_CPU0")
		)
		(pad "2" smd circle
			(at 0.40005 0 270)
			(size 0 0)
			(layers "F.Cu" "F.Mask" "F.Paste")
			(net "GND")
		)
	)
	(footprint ""
		(layer "F.Cu")
		(at 461.579214 -120.020334)
		(property "Reference" "C579"
			(at 0 0 0)
			(layer "F.SilkS")
			(hide yes)
			(effects
				(font
					(size 1.27 1.27)
				)
			)
		)
		(property "Value" ""
			(at 0 0 0)
			(layer "F.Fab")
			(effects
				(font
					(size 1.27 1.27)
				)
			)
		)
		(duplicate_pad_numbers_are_jumpers no)
		(fp_line
			(start -0.7874 -0.4064)
			(end 0.7874 -0.4064)
			(stroke
				(width 0.1524)
				(type default)
			)
			(layer "F.SilkS")
		)
		(fp_line
			(start -0.7874 0.4064)
			(end -0.7874 -0.4064)
			(stroke
				(width 0.1524)
				(type default)
			)
			(layer "F.SilkS")
		)
		(fp_line
			(start 0.7874 -0.4064)
			(end 0.7874 0.4064)
			(stroke
				(width 0.1524)
				(type default)
			)
			(layer "F.SilkS")
		)
		(fp_line
			(start 0.7874 0.4064)
			(end -0.7874 0.4064)
			(stroke
				(width 0.1524)
				(type default)
			)
			(layer "F.SilkS")
		)
		(fp_line
			(start -0.67945 -0.305054)
			(end -0.12065 -0.305054)
			(stroke
				(width 0.1)
				(type default)
			)
			(layer "F.Fab")
		)
		(fp_line
			(start -0.67945 0.3048)
			(end -0.67945 -0.305054)
			(stroke
				(width 0.1)
				(type default)
			)
			(layer "F.Fab")
		)
		(fp_line
			(start -0.12065 -0.305054)
			(end -0.12065 -0.2794)
			(stroke
				(width 0.1)
				(type default)
			)
			(layer "F.Fab")
		)
		(fp_line
			(start -0.12065 -0.2794)
			(end 0.12065 -0.2794)
			(stroke
				(width 0.1)
				(type default)
			)
			(layer "F.Fab")
		)
		(fp_line
			(start -0.12065 0.2794)
			(end -0.12065 0.3048)
			(stroke
				(width 0.1)
				(type default)
			)
			(layer "F.Fab")
		)
		(fp_line
			(start -0.12065 0.3048)
			(end -0.67945 0.3048)
			(stroke
				(width 0.1)
				(type default)
			)
			(layer "F.Fab")
		)
		(fp_line
			(start 0.120396 0.2794)
			(end -0.12065 0.2794)
			(stroke
				(width 0.1)
				(type default)
			)
			(layer "F.Fab")
		)
		(fp_line
			(start 0.120396 0.3048)
			(end 0.120396 0.2794)
			(stroke
				(width 0.1)
				(type default)
			)
			(layer "F.Fab")
		)
		(fp_line
			(start 0.12065 -0.3048)
			(end 0.67945 -0.3048)
			(stroke
				(width 0.1)
				(type default)
			)
			(layer "F.Fab")
		)
		(fp_line
			(start 0.12065 -0.2794)
			(end 0.12065 -0.3048)
			(stroke
				(width 0.1)
				(type default)
			)
			(layer "F.Fab")
		)
		(fp_line
			(start 0.67945 -0.3048)
			(end 0.67945 0.3048)
			(stroke
				(width 0.1)
				(type default)
			)
			(layer "F.Fab")
		)
		(fp_line
			(start 0.67945 0.3048)
			(end 0.120396 0.3048)
			(stroke
				(width 0.1)
				(type default)
			)
			(layer "F.Fab")
		)
		(pad "1" smd circle
			(at -0.40005 0)
			(size 0 0)
			(layers "F.Cu" "F.Mask" "F.Paste")
			(net "P3V3_AUX")
		)
		(pad "2" smd circle
			(at 0.40005 0)
			(size 0 0)
			(layers "F.Cu" "F.Mask" "F.Paste")
			(net "GND")
		)
	)
	(footprint ""
		(layer "F.Cu")
		(at 205.54188 -109.057948 90)
		(property "Reference" "Q33"
			(at 1.09601 -4.26466 0)
			(unlocked yes)
			(layer "F.SilkS")
			(effects
				(font
					(size 0.7874 0.5842)
					(thickness 0.1524)
				)
				(justify left)
			)
		)
		(property "Value" ""
			(at 0 0 90)
			(layer "F.Fab")
			(effects
				(font
					(size 1.27 1.27)
				)
			)
		)
		(duplicate_pad_numbers_are_jumpers no)
		(fp_line
			(start 1.603248 -1.500124)
			(end 1.603248 1.500124)
			(stroke
				(width 0.1524)
				(type default)
			)
			(layer "F.SilkS")
		)
		(fp_line
			(start -1.603248 -1.500124)
			(end 1.603248 -1.500124)
			(stroke
				(width 0.1524)
				(type default)
			)
			(layer "F.SilkS")
		)
		(fp_line
			(start 1.603248 1.500124)
			(end -1.603248 1.500124)
			(stroke
				(width 0.1524)
				(type default)
			)
			(layer "F.SilkS")
		)
		(fp_line
			(start -1.603248 1.500124)
			(end -1.603248 -1.500124)
			(stroke
				(width 0.1524)
				(type default)
			)
			(layer "F.SilkS")
		)
		(fp_line
			(start 0.700024 -1.500124)
			(end -0.700024 -1.500124)
			(stroke
				(width 0.1)
				(type default)
			)
			(layer "F.Fab")
		)
		(fp_line
			(start -0.700024 -1.500124)
			(end -0.700024 -1.169924)
			(stroke
				(width 0.1)
				(type default)
			)
			(layer "F.Fab")
		)
		(fp_line
			(start -0.700024 -1.169924)
			(end -1.249934 -1.169924)
			(stroke
				(width 0.1)
				(type default)
			)
			(layer "F.Fab")
		)
		(fp_line
			(start -1.249934 -1.169924)
			(end -1.249934 -0.729996)
			(stroke
				(width 0.1)
				(type default)
			)
			(layer "F.Fab")
		)
		(fp_line
			(start -0.6985 -0.729996)
			(end -0.6985 0.729996)
			(stroke
				(width 0.1)
				(type default)
			)
			(layer "F.Fab")
		)
		(fp_line
			(start -1.249934 -0.729996)
			(end -0.6985 -0.729996)
			(stroke
				(width 0.1)
				(type default)
			)
			(layer "F.Fab")
		)
		(fp_line
			(start 1.249934 -0.219964)
			(end 0.700024 -0.219964)
			(stroke
				(width 0.1)
				(type default)
			)
			(layer "F.Fab")
		)
		(fp_line
			(start 0.700024 -0.219964)
			(end 0.700024 -1.500124)
			(stroke
				(width 0.1)
				(type default)
			)
			(layer "F.Fab")
		)
		(fp_line
			(start 1.249934 0.219964)
			(end 1.249934 -0.219964)
			(stroke
				(width 0.1)
				(type default)
			)
			(layer "F.Fab")
		)
		(fp_line
			(start 0.700024 0.219964)
			(end 1.249934 0.219964)
			(stroke
				(width 0.1)
				(type default)
			)
			(layer "F.Fab")
		)
		(fp_line
			(start -0.6985 0.729996)
			(end -1.249934 0.729996)
			(stroke
				(width 0.1)
				(type default)
			)
			(layer "F.Fab")
		)
		(fp_line
			(start -1.249934 0.729996)
			(end -1.249934 1.169924)
			(stroke
				(width 0.1)
				(type default)
			)
			(layer "F.Fab")
		)
		(fp_line
			(start -0.700024 1.169924)
			(end -0.700024 1.500124)
			(stroke
				(width 0.1)
				(type default)
			)
			(layer "F.Fab")
		)
		(fp_line
			(start -1.249934 1.169924)
			(end -0.700024 1.169924)
			(stroke
				(width 0.1)
				(type default)
			)
			(layer "F.Fab")
		)
		(fp_line
			(start 0.700024 1.500124)
			(end 0.700024 0.219964)
			(stroke
				(width 0.1)
				(type default)
			)
			(layer "F.Fab")
		)
		(fp_line
			(start -0.700024 1.500124)
			(end 0.700024 1.500124)
			(stroke
				(width 0.1)
				(type default)
			)
			(layer "F.Fab")
		)
		(fp_rect
			(start -0.700024 -1.500124)
			(end 0.700024 1.500124)
			(stroke
				(width 0)
				(type default)
			)
			(fill no)
			(layer "F.Fab")
		)
		(pad "D" smd rect
			(at 0.999998 0)
			(size 0.8128 0.9144)
			(layers "F.Cu" "F.Mask" "F.Paste")
			(net "LED_CPU_RMCA_CATERR")
		)
		(pad "G" smd rect
			(at -0.999998 -0.94996)
			(size 0.8128 0.9144)
			(layers "F.Cu" "F.Mask" "F.Paste")
			(net "CPU_RMCA_CATERR_LVT3_N")
		)
		(pad "S" smd rect
			(at -0.999998 0.94996)
			(size 0.8128 0.9144)
			(layers "F.Cu" "F.Mask" "F.Paste")
			(net "LED_CPU_RMCA_CATERR_R")
		)
	)
	(footprint ""
		(layer "F.Cu")
		(at 120.603264 -38.005512)
		(property "Reference" "U248"
			(at -1.48336 1.88849 0)
			(unlocked yes)
			(layer "F.SilkS")
			(effects
				(font
					(size 0.7874 0.5842)
					(thickness 0.1524)
				)
				(justify left)
			)
		)
		(property "Value" ""
			(at 0 0 0)
			(layer "F.Fab")
			(effects
				(font
					(size 1.27 1.27)
				)
			)
		)
		(duplicate_pad_numbers_are_jumpers no)
		(fp_line
			(start -1.4986 -1.100074)
			(end 1.4986 -1.100074)
			(stroke
				(width 0.1524)
				(type default)
			)
			(layer "F.SilkS")
		)
		(fp_line
			(start -1.4986 1.100074)
			(end -1.4986 -1.100074)
			(stroke
				(width 0.1524)
				(type default)
			)
			(layer "F.SilkS")
		)
		(fp_line
			(start 1.4986 -1.100074)
			(end 1.4986 1.100074)
			(stroke
				(width 0.1524)
				(type default)
			)
			(layer "F.SilkS")
		)
		(fp_line
			(start 1.4986 1.100074)
			(end -1.4986 1.100074)
			(stroke
				(width 0.1524)
				(type default)
			)
			(layer "F.SilkS")
		)
		(fp_poly
			(pts
				(xy -0.715772 -1.863852) (xy -1.04394 -1.310132) (xy -1.340612 -1.863852)
			)
			(stroke
				(width 0)
				(type default)
			)
			(fill yes)
			(layer "F.SilkS")
		)
		(fp_line
			(start -0.67437 -1.100074)
			(end 0.67437 -1.100074)
			(stroke
				(width 0.1)
				(type default)
			)
			(layer "F.Fab")
		)
		(fp_line
			(start -0.67437 1.100074)
			(end -0.67437 -1.100074)
			(stroke
				(width 0.1)
				(type default)
			)
			(layer "F.Fab")
		)
		(fp_line
			(start 0.67437 -1.100074)
			(end 0.67437 1.100074)
			(stroke
				(width 0.1)
				(type default)
			)
			(layer "F.Fab")
		)
		(fp_line
			(start 0.67437 1.100074)
			(end -0.67437 1.100074)
			(stroke
				(width 0.1)
				(type default)
			)
			(layer "F.Fab")
		)
		(fp_poly
			(pts
				(xy -2.20472 -0.338328) (xy -2.20472 -0.963168) (xy -1.651 -0.635)
			)
			(stroke
				(width 0)
				(type default)
			)
			(fill yes)
			(layer "F.Fab")
		)
		(pad "1" smd rect
			(at -0.889 -0.649986)
			(size 1.016 0.381)
			(layers "F.Cu" "F.Mask" "F.Paste")
			(net "GPU_FPGA_READY_R_N")
		)
		(pad "2" smd rect
			(at -0.889 0)
			(size 1.016 0.381)
			(layers "F.Cu" "F.Mask" "F.Paste")
			(net "CLK_GEN2_GPU_FPGA_OE_R2_N")
		)
		(pad "3" smd rect
			(at -0.889 0.649986)
			(size 1.016 0.381)
			(layers "F.Cu" "F.Mask" "F.Paste")
			(net "GND")
		)
		(pad "4" smd rect
			(at 0.889 0.649986)
			(size 1.016 0.381)
			(layers "F.Cu" "F.Mask" "F.Paste")
			(net "CLK_GEN2_GPU_FPGA_OE_OR_N")
		)
		(pad "5" smd rect
			(at 0.889 -0.649986)
			(size 1.016 0.381)
			(layers "F.Cu" "F.Mask" "F.Paste")
			(net "P3V3_AUX")
		)
	)
)
